(kicad_pcb
	(version 20260206)
	(generator "pcbnew")
	(generator_version "10.0")
	(general
		(thickness 1.6)
		(legacy_teardrops no)
	)
	(paper "A4")
	(title_block
		(title "01162023_DA0F0TEBIF0_F0T_Expander_BD_F_brd_V02_OCP.brd")
		(comment 1 "Grand Teton / footprints 2578-2585 of 9728")
	)
	(layers
		(0 "F.Cu" signal "TOP")
		(4 "In1.Cu" signal "GND")
		(6 "In2.Cu" signal "VCC")
		(8 "In3.Cu" signal "VCC1")
		(10 "In4.Cu" signal "GND1")
		(12 "In5.Cu" signal "IN1")
		(14 "In6.Cu" signal "GND2")
		(16 "In7.Cu" signal "IN2")
		(18 "In8.Cu" signal "GND3")
		(20 "In9.Cu" signal "IN3")
		(22 "In10.Cu" signal "GND4")
		(24 "In11.Cu" signal "IN4")
		(26 "In12.Cu" signal "GND5")
		(28 "In13.Cu" signal "IN5")
		(30 "In14.Cu" signal "GND6")
		(32 "In15.Cu" signal "IN6")
		(34 "In16.Cu" signal "GND7")
		(2 "B.Cu" signal "BOTTOM")
		(9 "F.Adhes" user "F.Adhesive")
		(11 "B.Adhes" user "B.Adhesive")
		(13 "F.Paste" user "Package Geometry/Pastemask Top")
		(15 "B.Paste" user "Package Geometry/Pastemask Bottom")
		(5 "F.SilkS" user "Ref Des/Silkscreen Top")
		(7 "B.SilkS" user "Ref Des/Silkscreen Bottom")
		(1 "F.Mask" user "Board Geometry/Soldermask Top")
		(3 "B.Mask" user "Board Geometry/Soldermask Bottom")
		(17 "Dwgs.User" user "User.Drawings")
		(19 "Cmts.User" user "User.Comments")
		(21 "Eco1.User" user "User.Eco1")
		(23 "Eco2.User" user "User.Eco2")
		(25 "Edge.Cuts" user "Board Geometry/Outline")
		(27 "Margin" user)
		(31 "F.CrtYd" user "Package Geometry/Place Bound Top")
		(29 "B.CrtYd" user "Package Geometry/Place Bound Bottom")
		(35 "F.Fab" user "Ref Des/Assembly Top")
		(33 "B.Fab" user "Ref Des/Assembly Bottom")
	)
	(footprint ""
		(layer "F.Cu")
		(at 38.608 -158.3944 180)
		(property "Reference" "R11"
			(at 0 0 180)
			(layer "F.SilkS")
			(hide yes)
			(effects
				(font
					(size 1.27 1.27)
				)
			)
		)
		(property "Value" ""
			(at 0 0 180)
			(layer "F.Fab")
			(effects
				(font
					(size 1.27 1.27)
				)
			)
		)
		(duplicate_pad_numbers_are_jumpers no)
		(fp_line
			(start 0.7874 0.4064)
			(end -0.7874 0.4064)
			(stroke
				(width 0.1524)
				(type default)
			)
			(layer "F.SilkS")
		)
		(fp_line
			(start 0.7874 -0.4064)
			(end 0.7874 0.4064)
			(stroke
				(width 0.1524)
				(type default)
			)
			(layer "F.SilkS")
		)
		(fp_line
			(start -0.7874 0.4064)
			(end -0.7874 -0.4064)
			(stroke
				(width 0.1524)
				(type default)
			)
			(layer "F.SilkS")
		)
		(fp_line
			(start -0.7874 -0.4064)
			(end 0.7874 -0.4064)
			(stroke
				(width 0.1524)
				(type default)
			)
			(layer "F.SilkS")
		)
		(fp_line
			(start 0.67945 0.3048)
			(end 0.120396 0.3048)
			(stroke
				(width 0.1)
				(type default)
			)
			(layer "F.Fab")
		)
		(fp_line
			(start 0.67945 -0.3048)
			(end 0.67945 0.3048)
			(stroke
				(width 0.1)
				(type default)
			)
			(layer "F.Fab")
		)
		(fp_line
			(start 0.12065 -0.2794)
			(end 0.12065 -0.3048)
			(stroke
				(width 0.1)
				(type default)
			)
			(layer "F.Fab")
		)
		(fp_line
			(start 0.12065 -0.3048)
			(end 0.67945 -0.3048)
			(stroke
				(width 0.1)
				(type default)
			)
			(layer "F.Fab")
		)
		(fp_line
			(start 0.120396 0.3048)
			(end 0.120396 0.2794)
			(stroke
				(width 0.1)
				(type default)
			)
			(layer "F.Fab")
		)
		(fp_line
			(start 0.120396 0.2794)
			(end -0.12065 0.2794)
			(stroke
				(width 0.1)
				(type default)
			)
			(layer "F.Fab")
		)
		(fp_line
			(start -0.12065 0.3048)
			(end -0.67945 0.3048)
			(stroke
				(width 0.1)
				(type default)
			)
			(layer "F.Fab")
		)
		(fp_line
			(start -0.12065 0.2794)
			(end -0.12065 0.3048)
			(stroke
				(width 0.1)
				(type default)
			)
			(layer "F.Fab")
		)
		(fp_line
			(start -0.12065 -0.2794)
			(end 0.12065 -0.2794)
			(stroke
				(width 0.1)
				(type default)
			)
			(layer "F.Fab")
		)
		(fp_line
			(start -0.12065 -0.305054)
			(end -0.12065 -0.2794)
			(stroke
				(width 0.1)
				(type default)
			)
			(layer "F.Fab")
		)
		(fp_line
			(start -0.67945 0.3048)
			(end -0.67945 -0.305054)
			(stroke
				(width 0.1)
				(type default)
			)
			(layer "F.Fab")
		)
		(fp_line
			(start -0.67945 -0.305054)
			(end -0.12065 -0.305054)
			(stroke
				(width 0.1)
				(type default)
			)
			(layer "F.Fab")
		)
		(pad "1" smd circle
			(at -0.40005 0 180)
			(size 0 0)
			(layers "F.Cu" "F.Mask" "F.Paste")
			(net "NIC0_LD_N")
		)
		(pad "2" smd circle
			(at 0.40005 0 180)
			(size 0 0)
			(layers "F.Cu" "F.Mask" "F.Paste")
			(net "P3V3_NIC0")
		)
	)
	(footprint ""
		(layer "F.Cu")
		(at 426.543724 -45.88891)
		(property "Reference" "R664"
			(at 0 0 0)
			(layer "F.SilkS")
			(hide yes)
			(effects
				(font
					(size 1.27 1.27)
				)
			)
		)
		(property "Value" ""
			(at 0 0 0)
			(layer "F.Fab")
			(effects
				(font
					(size 1.27 1.27)
				)
			)
		)
		(duplicate_pad_numbers_are_jumpers no)
		(fp_line
			(start -0.7874 -0.4064)
			(end 0.7874 -0.4064)
			(stroke
				(width 0.1524)
				(type default)
			)
			(layer "F.SilkS")
		)
		(fp_line
			(start -0.7874 0.4064)
			(end -0.7874 -0.4064)
			(stroke
				(width 0.1524)
				(type default)
			)
			(layer "F.SilkS")
		)
		(fp_line
			(start 0.7874 -0.4064)
			(end 0.7874 0.4064)
			(stroke
				(width 0.1524)
				(type default)
			)
			(layer "F.SilkS")
		)
		(fp_line
			(start 0.7874 0.4064)
			(end -0.7874 0.4064)
			(stroke
				(width 0.1524)
				(type default)
			)
			(layer "F.SilkS")
		)
		(fp_line
			(start -0.67945 -0.305054)
			(end -0.12065 -0.305054)
			(stroke
				(width 0.1)
				(type default)
			)
			(layer "F.Fab")
		)
		(fp_line
			(start -0.67945 0.3048)
			(end -0.67945 -0.305054)
			(stroke
				(width 0.1)
				(type default)
			)
			(layer "F.Fab")
		)
		(fp_line
			(start -0.12065 -0.305054)
			(end -0.12065 -0.2794)
			(stroke
				(width 0.1)
				(type default)
			)
			(layer "F.Fab")
		)
		(fp_line
			(start -0.12065 -0.2794)
			(end 0.12065 -0.2794)
			(stroke
				(width 0.1)
				(type default)
			)
			(layer "F.Fab")
		)
		(fp_line
			(start -0.12065 0.2794)
			(end -0.12065 0.3048)
			(stroke
				(width 0.1)
				(type default)
			)
			(layer "F.Fab")
		)
		(fp_line
			(start -0.12065 0.3048)
			(end -0.67945 0.3048)
			(stroke
				(width 0.1)
				(type default)
			)
			(layer "F.Fab")
		)
		(fp_line
			(start 0.120396 0.2794)
			(end -0.12065 0.2794)
			(stroke
				(width 0.1)
				(type default)
			)
			(layer "F.Fab")
		)
		(fp_line
			(start 0.120396 0.3048)
			(end 0.120396 0.2794)
			(stroke
				(width 0.1)
				(type default)
			)
			(layer "F.Fab")
		)
		(fp_line
			(start 0.12065 -0.3048)
			(end 0.67945 -0.3048)
			(stroke
				(width 0.1)
				(type default)
			)
			(layer "F.Fab")
		)
		(fp_line
			(start 0.12065 -0.2794)
			(end 0.12065 -0.3048)
			(stroke
				(width 0.1)
				(type default)
			)
			(layer "F.Fab")
		)
		(fp_line
			(start 0.67945 -0.3048)
			(end 0.67945 0.3048)
			(stroke
				(width 0.1)
				(type default)
			)
			(layer "F.Fab")
		)
		(fp_line
			(start 0.67945 0.3048)
			(end 0.120396 0.3048)
			(stroke
				(width 0.1)
				(type default)
			)
			(layer "F.Fab")
		)
		(pad "1" smd circle
			(at -0.40005 0)
			(size 0 0)
			(layers "F.Cu" "F.Mask" "F.Paste")
			(net "SSD14_ADC_A0")
		)
		(pad "2" smd circle
			(at 0.40005 0)
			(size 0 0)
			(layers "F.Cu" "F.Mask" "F.Paste")
			(net "GND")
		)
	)
	(footprint ""
		(layer "F.Cu")
		(at 418.596572 -356.244906 90)
		(property "Reference" "C2449"
			(at 0 0 90)
			(layer "F.SilkS")
			(hide yes)
			(effects
				(font
					(size 1.27 1.27)
				)
			)
		)
		(property "Value" ""
			(at 0 0 90)
			(layer "F.Fab")
			(effects
				(font
					(size 1.27 1.27)
				)
			)
		)
		(duplicate_pad_numbers_are_jumpers no)
		(fp_line
			(start 0.299974 -0.150114)
			(end 0.299974 0.150114)
			(stroke
				(width 0.1)
				(type default)
			)
			(layer "F.Fab")
		)
		(fp_line
			(start -0.299974 -0.150114)
			(end 0.299974 -0.150114)
			(stroke
				(width 0.1)
				(type default)
			)
			(layer "F.Fab")
		)
		(fp_line
			(start 0.299974 0.150114)
			(end -0.299974 0.150114)
			(stroke
				(width 0.1)
				(type default)
			)
			(layer "F.Fab")
		)
		(fp_line
			(start -0.299974 0.150114)
			(end -0.299974 -0.150114)
			(stroke
				(width 0.1)
				(type default)
			)
			(layer "F.Fab")
		)
		(pad "1" smd rect
			(at -0.2667 0 90)
			(size 0.3048 0.381)
			(layers "F.Cu" "F.Mask" "F.Paste")
			(net "P5E_PEX3_STN4_TX_DP<74>")
		)
		(pad "2" smd rect
			(at 0.2667 0 90)
			(size 0.3048 0.381)
			(layers "F.Cu" "F.Mask" "F.Paste")
			(net "P5E_PEX3_STN4_TX_C_DP<74>")
		)
	)
	(footprint ""
		(layer "F.Cu")
		(at 312.21934 -130.794506 180)
		(property "Reference" "C445"
			(at 0 0 180)
			(layer "F.SilkS")
			(hide yes)
			(effects
				(font
					(size 1.27 1.27)
				)
			)
		)
		(property "Value" ""
			(at 0 0 180)
			(layer "F.Fab")
			(effects
				(font
					(size 1.27 1.27)
				)
			)
		)
		(duplicate_pad_numbers_are_jumpers no)
		(fp_line
			(start 0.299974 0.150114)
			(end -0.299974 0.150114)
			(stroke
				(width 0.1)
				(type default)
			)
			(layer "F.Fab")
		)
		(fp_line
			(start 0.299974 -0.150114)
			(end 0.299974 0.150114)
			(stroke
				(width 0.1)
				(type default)
			)
			(layer "F.Fab")
		)
		(fp_line
			(start -0.299974 0.150114)
			(end -0.299974 -0.150114)
			(stroke
				(width 0.1)
				(type default)
			)
			(layer "F.Fab")
		)
		(fp_line
			(start -0.299974 -0.150114)
			(end 0.299974 -0.150114)
			(stroke
				(width 0.1)
				(type default)
			)
			(layer "F.Fab")
		)
		(pad "1" smd rect
			(at -0.2667 0 180)
			(size 0.3048 0.381)
			(layers "F.Cu" "F.Mask" "F.Paste")
			(net "P5E_PEX2_STN0_TX_DP<4>")
		)
		(pad "2" smd rect
			(at 0.2667 0 180)
			(size 0.3048 0.381)
			(layers "F.Cu" "F.Mask" "F.Paste")
			(net "P5E_PEX2_STN0_TX_C_DP<4>")
		)
	)
	(footprint ""
		(layer "F.Cu")
		(at 457.935838 -314.547758)
		(property "Reference" "PC267"
			(at 0 0 0)
			(layer "F.SilkS")
			(hide yes)
			(effects
				(font
					(size 1.27 1.27)
				)
			)
		)
		(property "Value" ""
			(at 0 0 0)
			(layer "F.Fab")
			(effects
				(font
					(size 1.27 1.27)
				)
			)
		)
		(duplicate_pad_numbers_are_jumpers no)
		(fp_line
			(start -1.524 -0.762)
			(end 1.524 -0.762)
			(stroke
				(width 0.1524)
				(type default)
			)
			(layer "F.SilkS")
		)
		(fp_line
			(start -1.524 0.762)
			(end -1.524 -0.762)
			(stroke
				(width 0.1524)
				(type default)
			)
			(layer "F.SilkS")
		)
		(fp_line
			(start 1.524 -0.762)
			(end 1.524 0.762)
			(stroke
				(width 0.1524)
				(type default)
			)
			(layer "F.SilkS")
		)
		(fp_line
			(start 1.524 0.762)
			(end -1.524 0.762)
			(stroke
				(width 0.1524)
				(type default)
			)
			(layer "F.SilkS")
		)
		(fp_line
			(start -1.1049 -0.724916)
			(end -1.1049 0.724916)
			(stroke
				(width 0.1)
				(type default)
			)
			(layer "F.Fab")
		)
		(fp_line
			(start -1.1049 0.724916)
			(end 1.1049 0.724916)
			(stroke
				(width 0.1)
				(type default)
			)
			(layer "F.Fab")
		)
		(fp_line
			(start 1.1049 -0.724916)
			(end -1.1049 -0.724916)
			(stroke
				(width 0.1)
				(type default)
			)
			(layer "F.Fab")
		)
		(fp_line
			(start 1.1049 0.724916)
			(end 1.1049 -0.724916)
			(stroke
				(width 0.1)
				(type default)
			)
			(layer "F.Fab")
		)
		(pad "1" smd rect
			(at -0.889 0 180)
			(size 1.016 1.27)
			(layers "F.Cu" "F.Mask" "F.Paste")
			(net "SW_P12V_P1V25_PEX3_FLT")
		)
		(pad "2" smd rect
			(at 0.889 0 180)
			(size 1.016 1.27)
			(layers "F.Cu" "F.Mask" "F.Paste")
			(net "GND")
		)
	)
	(footprint ""
		(layer "F.Cu")
		(at 405.694134 -29.507688 -90)
		(property "Reference" "PC972"
			(at 0 0 270)
			(layer "F.SilkS")
			(hide yes)
			(effects
				(font
					(size 1.27 1.27)
				)
			)
		)
		(property "Value" ""
			(at 0 0 270)
			(layer "F.Fab")
			(effects
				(font
					(size 1.27 1.27)
				)
			)
		)
		(duplicate_pad_numbers_are_jumpers no)
		(fp_line
			(start -1.524 0.762)
			(end -1.524 -0.762)
			(stroke
				(width 0.1524)
				(type default)
			)
			(layer "F.SilkS")
		)
		(fp_line
			(start 1.524 0.762)
			(end -1.524 0.762)
			(stroke
				(width 0.1524)
				(type default)
			)
			(layer "F.SilkS")
		)
		(fp_line
			(start -1.524 -0.762)
			(end 1.524 -0.762)
			(stroke
				(width 0.1524)
				(type default)
			)
			(layer "F.SilkS")
		)
		(fp_line
			(start 1.524 -0.762)
			(end 1.524 0.762)
			(stroke
				(width 0.1524)
				(type default)
			)
			(layer "F.SilkS")
		)
		(fp_line
			(start -1.1049 0.724916)
			(end 1.1049 0.724916)
			(stroke
				(width 0.1)
				(type default)
			)
			(layer "F.Fab")
		)
		(fp_line
			(start 1.1049 0.724916)
			(end 1.1049 -0.724916)
			(stroke
				(width 0.1)
				(type default)
			)
			(layer "F.Fab")
		)
		(fp_line
			(start -1.1049 -0.724916)
			(end -1.1049 0.724916)
			(stroke
				(width 0.1)
				(type default)
			)
			(layer "F.Fab")
		)
		(fp_line
			(start 1.1049 -0.724916)
			(end -1.1049 -0.724916)
			(stroke
				(width 0.1)
				(type default)
			)
			(layer "F.Fab")
		)
		(pad "1" smd rect
			(at -0.889 0 90)
			(size 1.016 1.27)
			(layers "F.Cu" "F.Mask" "F.Paste")
			(net "P3V3_SSD14")
		)
		(pad "2" smd rect
			(at 0.889 0 90)
			(size 1.016 1.27)
			(layers "F.Cu" "F.Mask" "F.Paste")
			(net "GND")
		)
	)
	(footprint ""
		(layer "F.Cu")
		(at 258.44373 -48.93691 180)
		(property "Reference" "R5898"
			(at 0 0 180)
			(layer "F.SilkS")
			(hide yes)
			(effects
				(font
					(size 1.27 1.27)
				)
			)
		)
		(property "Value" ""
			(at 0 0 180)
			(layer "F.Fab")
			(effects
				(font
					(size 1.27 1.27)
				)
			)
		)
		(duplicate_pad_numbers_are_jumpers no)
		(fp_line
			(start 0.7874 0.4064)
			(end -0.7874 0.4064)
			(stroke
				(width 0.1524)
				(type default)
			)
			(layer "F.SilkS")
		)
		(fp_line
			(start 0.7874 -0.4064)
			(end 0.7874 0.4064)
			(stroke
				(width 0.1524)
				(type default)
			)
			(layer "F.SilkS")
		)
		(fp_line
			(start -0.7874 0.4064)
			(end -0.7874 -0.4064)
			(stroke
				(width 0.1524)
				(type default)
			)
			(layer "F.SilkS")
		)
		(fp_line
			(start -0.7874 -0.4064)
			(end 0.7874 -0.4064)
			(stroke
				(width 0.1524)
				(type default)
			)
			(layer "F.SilkS")
		)
		(fp_line
			(start 0.67945 0.3048)
			(end 0.120396 0.3048)
			(stroke
				(width 0.1)
				(type default)
			)
			(layer "F.Fab")
		)
		(fp_line
			(start 0.67945 -0.3048)
			(end 0.67945 0.3048)
			(stroke
				(width 0.1)
				(type default)
			)
			(layer "F.Fab")
		)
		(fp_line
			(start 0.12065 -0.2794)
			(end 0.12065 -0.3048)
			(stroke
				(width 0.1)
				(type default)
			)
			(layer "F.Fab")
		)
		(fp_line
			(start 0.12065 -0.3048)
			(end 0.67945 -0.3048)
			(stroke
				(width 0.1)
				(type default)
			)
			(layer "F.Fab")
		)
		(fp_line
			(start 0.120396 0.3048)
			(end 0.120396 0.2794)
			(stroke
				(width 0.1)
				(type default)
			)
			(layer "F.Fab")
		)
		(fp_line
			(start 0.120396 0.2794)
			(end -0.12065 0.2794)
			(stroke
				(width 0.1)
				(type default)
			)
			(layer "F.Fab")
		)
		(fp_line
			(start -0.12065 0.3048)
			(end -0.67945 0.3048)
			(stroke
				(width 0.1)
				(type default)
			)
			(layer "F.Fab")
		)
		(fp_line
			(start -0.12065 0.2794)
			(end -0.12065 0.3048)
			(stroke
				(width 0.1)
				(type default)
			)
			(layer "F.Fab")
		)
		(fp_line
			(start -0.12065 -0.2794)
			(end 0.12065 -0.2794)
			(stroke
				(width 0.1)
				(type default)
			)
			(layer "F.Fab")
		)
		(fp_line
			(start -0.12065 -0.305054)
			(end -0.12065 -0.2794)
			(stroke
				(width 0.1)
				(type default)
			)
			(layer "F.Fab")
		)
		(fp_line
			(start -0.67945 0.3048)
			(end -0.67945 -0.305054)
			(stroke
				(width 0.1)
				(type default)
			)
			(layer "F.Fab")
		)
		(fp_line
			(start -0.67945 -0.305054)
			(end -0.12065 -0.305054)
			(stroke
				(width 0.1)
				(type default)
			)
			(layer "F.Fab")
		)
		(pad "1" smd circle
			(at -0.40005 0 180)
			(size 0 0)
			(layers "F.Cu" "F.Mask" "F.Paste")
			(net "SSD8_ADC_A1")
		)
		(pad "2" smd circle
			(at 0.40005 0 180)
			(size 0 0)
			(layers "F.Cu" "F.Mask" "F.Paste")
			(net "SMB_SSD8_ADC_SDA")
		)
	)
	(footprint ""
		(layer "F.Cu")
		(at 13.0175 -313.890152)
		(property "Reference" "PC207"
			(at 0 0 0)
			(layer "F.SilkS")
			(hide yes)
			(effects
				(font
					(size 1.27 1.27)
				)
			)
		)
		(property "Value" ""
			(at 0 0 0)
			(layer "F.Fab")
			(effects
				(font
					(size 1.27 1.27)
				)
			)
		)
		(duplicate_pad_numbers_are_jumpers no)
		(fp_line
			(start -1.524 -0.762)
			(end 1.524 -0.762)
			(stroke
				(width 0.1524)
				(type default)
			)
			(layer "F.SilkS")
		)
		(fp_line
			(start -1.524 0.762)
			(end -1.524 -0.762)
			(stroke
				(width 0.1524)
				(type default)
			)
			(layer "F.SilkS")
		)
		(fp_line
			(start 1.524 -0.762)
			(end 1.524 0.762)
			(stroke
				(width 0.1524)
				(type default)
			)
			(layer "F.SilkS")
		)
		(fp_line
			(start 1.524 0.762)
			(end -1.524 0.762)
			(stroke
				(width 0.1524)
				(type default)
			)
			(layer "F.SilkS")
		)
		(fp_line
			(start -1.1049 -0.724916)
			(end -1.1049 0.724916)
			(stroke
				(width 0.1)
				(type default)
			)
			(layer "F.Fab")
		)
		(fp_line
			(start -1.1049 0.724916)
			(end 1.1049 0.724916)
			(stroke
				(width 0.1)
				(type default)
			)
			(layer "F.Fab")
		)
		(fp_line
			(start 1.1049 -0.724916)
			(end -1.1049 -0.724916)
			(stroke
				(width 0.1)
				(type default)
			)
			(layer "F.Fab")
		)
		(fp_line
			(start 1.1049 0.724916)
			(end 1.1049 -0.724916)
			(stroke
				(width 0.1)
				(type default)
			)
			(layer "F.Fab")
		)
		(pad "1" smd rect
			(at -0.889 0 180)
			(size 1.016 1.27)
			(layers "F.Cu" "F.Mask" "F.Paste")
			(net "SW_P12V_P1V25_PEX0_FLT")
		)
		(pad "2" smd rect
			(at 0.889 0 180)
			(size 1.016 1.27)
			(layers "F.Cu" "F.Mask" "F.Paste")
			(net "GND")
		)
	)
)
